(kicad_pcb
	(version 20221018)
	(generator pcbnew)
	(general
    (thickness 1.62)
  )
	(paper "A4")
	(title_block
    (title "ECP5 - Datacenter Secure Control Module (DC-SCM)")
    (date "2024-07-01")
    (rev "1.2.1")
		(comment 9 "footprint 183 of 506 (J5), pads 118-168 of 168")
	)
	(layers
    (0 "F.Cu" signal)
    (1 "In1.Cu" power)
    (2 "In2.Cu" signal)
    (3 "In3.Cu" power)
    (4 "In4.Cu" power)
    (5 "In5.Cu" signal)
    (6 "In6.Cu" power)
    (31 "B.Cu" signal)
    (32 "B.Adhes" user "B.Adhesive")
    (33 "F.Adhes" user "F.Adhesive")
    (34 "B.Paste" user)
    (35 "F.Paste" user)
    (36 "B.SilkS" user "B.Silkscreen")
    (37 "F.SilkS" user "F.Silkscreen")
    (38 "B.Mask" user)
    (39 "F.Mask" user)
    (40 "Dwgs.User" user "User.Drawings")
    (41 "Cmts.User" user "User.Comments")
    (42 "Eco1.User" user "User.Eco1")
    (43 "Eco2.User" user "User.Eco2")
    (44 "Edge.Cuts" user)
    (45 "Margin" user)
    (46 "B.CrtYd" user "B.Courtyard")
    (47 "F.CrtYd" user "F.Courtyard")
    (48 "B.Fab" user)
    (49 "F.Fab" user)
  )
	(footprint "antmicro-footprints:SFF-TA-1002-4C+"
    (layer "F.Cu")
    (at 104.89 177.345)
    (property "Author" "Antmicro")
    (property "DNP" "DNP")
    (property "License" "Apache-2.0")
    (property "MPN" "SFF-TA-1002-4C+")
    (property "Manufacturer" "Amphenol")
    (property "Sheetfile" "edge-connector.kicad_sch")
    (property "Sheetname" "Edge connector")
    (property "ki_description" "PCI connector")
    (property "ki_keywords" "CONNECTOR")
    (attr exclude_from_pos_files)
    (fp_text reference "J5" (at -0.83 -8.9) (layer "F.SilkS")
        (effects (font (size 0.7 0.7) (thickness 0.127)))
    )
    (fp_text value "SFF-TA-1002-4C+" (at -24.2 4.8) (layer "F.Fab")
        (effects (font (size 1 1) (thickness 0.15)))
    )
    (pad "B48" smd rect (at 17.7 -0.2) (size 0.38 1.72) (layers "F.Cu" "F.Mask")
      (net 97 "QSPI1_D3") (pinfunction "B48") (pintype "passive"))
    (pad "B49" smd rect (at 18.3 0) (size 0.38 2.12) (layers "F.Cu" "F.Mask")
      (net 1 "GND") (pinfunction "B49") (pintype "passive"))
    (pad "B50" smd rect (at 18.9 -0.2) (size 0.38 1.72) (layers "F.Cu" "F.Mask")
      (net 98 "USB2_DP") (pinfunction "B50") (pintype "passive"))
    (pad "B51" smd rect (at 19.5 -0.2) (size 0.38 1.72) (layers "F.Cu" "F.Mask")
      (net 99 "USB2_DN") (pinfunction "B51") (pintype "passive"))
    (pad "B52" smd rect (at 20.1 0) (size 0.38 2.12) (layers "F.Cu" "F.Mask")
      (net 1 "GND") (pinfunction "B52") (pintype "passive"))
    (pad "B53" smd rect (at 20.7 -0.2) (size 0.38 1.72) (layers "F.Cu" "F.Mask")
      (net 100 "USB1_DP") (pinfunction "B53") (pintype "passive"))
    (pad "B54" smd rect (at 21.3 -0.2) (size 0.38 1.72) (layers "F.Cu" "F.Mask")
      (net 101 "USB1_DN") (pinfunction "B54") (pintype "passive"))
    (pad "B55" smd rect (at 21.9 0) (size 0.38 2.12) (layers "F.Cu" "F.Mask")
      (net 1 "GND") (pinfunction "B55") (pintype "passive"))
    (pad "B56" smd rect (at 22.5 -0.2) (size 0.38 1.72) (layers "F.Cu" "F.Mask")
      (net 264 "CLK_PCIE_x4_DP") (pinfunction "B56") (pintype "passive"))
    (pad "B57" smd rect (at 23.1 -0.2) (size 0.38 1.72) (layers "F.Cu" "F.Mask")
      (net 266 "CLK_PCIE_x4_DN") (pinfunction "B57") (pintype "passive"))
    (pad "B58" smd rect (at 23.7 0) (size 0.38 2.12) (layers "F.Cu" "F.Mask")
      (net 1 "GND") (pinfunction "B58") (pintype "passive"))
    (pad "B59" smd rect (at 24.3 -0.2) (size 0.38 1.72) (layers "F.Cu" "F.Mask")
      (net 688 "PCIE_HPM_TX0_P") (pinfunction "B59") (pintype "passive"))
    (pad "B60" smd rect (at 24.9 -0.2) (size 0.38 1.72) (layers "F.Cu" "F.Mask")
      (net 692 "PCIE_HPM_TX0_N") (pinfunction "B60") (pintype "passive"))
    (pad "B61" smd rect (at 25.5 0) (size 0.38 2.12) (layers "F.Cu" "F.Mask")
      (net 1 "GND") (pinfunction "B61") (pintype "passive"))
    (pad "B62" smd rect (at 26.1 -0.2) (size 0.38 1.72) (layers "F.Cu" "F.Mask")
      (net 689 "PCIE_HPM_TX1_P") (pinfunction "B62") (pintype "passive"))
    (pad "B63" smd rect (at 26.7 -0.2) (size 0.38 1.72) (layers "F.Cu" "F.Mask")
      (net 693 "PCIE_HPM_TX1_N") (pinfunction "B63") (pintype "passive"))
    (pad "B64" smd rect (at 27.3 0) (size 0.38 2.12) (layers "F.Cu" "F.Mask")
      (net 1 "GND") (pinfunction "B64") (pintype "passive"))
    (pad "B65" smd rect (at 27.9 -0.2) (size 0.38 1.72) (layers "F.Cu" "F.Mask")
      (net 690 "PCIE_HPM_TX2_P") (pinfunction "B65") (pintype "passive"))
    (pad "B66" smd rect (at 28.5 -0.2) (size 0.38 1.72) (layers "F.Cu" "F.Mask")
      (net 694 "PCIE_HPM_TX2_N") (pinfunction "B66") (pintype "passive"))
    (pad "B67" smd rect (at 29.1 0) (size 0.38 2.12) (layers "F.Cu" "F.Mask")
      (net 1 "GND") (pinfunction "B67") (pintype "passive"))
    (pad "B68" smd rect (at 29.7 -0.2) (size 0.38 1.72) (layers "F.Cu" "F.Mask")
      (net 691 "PCIE_HPM_TX3_P") (pinfunction "B68") (pintype "passive"))
    (pad "B69" smd rect (at 30.3 -0.2) (size 0.38 1.72) (layers "F.Cu" "F.Mask")
      (net 695 "PCIE_HPM_TX3_N") (pinfunction "B69") (pintype "passive"))
    (pad "B70" smd rect (at 30.9 0) (size 0.38 2.12) (layers "F.Cu" "F.Mask")
      (net 1 "GND") (pinfunction "B70") (pintype "passive"))
    (pad "OA1" smd rect (at -30.4 -0.2) (size 0.38 1.72) (layers "B.Cu" "B.Mask")
      (net 57 "P12V_AUX") (pinfunction "OA1") (pintype "passive"))
    (pad "OA2" smd rect (at -29.8 -0.2) (size 0.38 1.72) (layers "B.Cu" "B.Mask")
      (net 57 "P12V_AUX") (pinfunction "OA2") (pintype "passive"))
    (pad "OA3" smd rect (at -29.2 0) (size 0.38 2.12) (layers "B.Cu" "B.Mask")
      (net 1 "GND") (pinfunction "OA3") (pintype "passive"))
    (pad "OA4" smd rect (at -28.6 0) (size 0.38 2.12) (layers "B.Cu" "B.Mask")
      (net 1 "GND") (pinfunction "OA4") (pintype "passive"))
    (pad "OA5" smd rect (at -28 -0.2) (size 0.38 1.72) (layers "B.Cu" "B.Mask")
      (net 206 "I3C[0]_SCL_1V0") (pinfunction "OA5") (pintype "passive"))
    (pad "OA6" smd rect (at -27.4 -0.2) (size 0.38 1.72) (layers "B.Cu" "B.Mask")
      (net 205 "I3C[0]_SDA_1V0") (pinfunction "OA6") (pintype "passive"))
    (pad "OA7" smd rect (at -26.8 -0.2) (size 0.38 1.72) (layers "B.Cu" "B.Mask")
      (net 208 "I3C[1]_SCL_1V0") (pinfunction "OA7") (pintype "passive"))
    (pad "OA8" smd rect (at -26.2 -0.2) (size 0.38 1.72) (layers "B.Cu" "B.Mask")
      (net 207 "I3C[1]_SDA_1V0") (pinfunction "OA8") (pintype "passive"))
    (pad "OA9" smd rect (at -25.6 -0.2) (size 0.38 1.72) (layers "B.Cu" "B.Mask")
      (net 210 "I3C[2]_SCL_1V0") (pinfunction "OA9") (pintype "passive"))
    (pad "OA10" smd rect (at -25 -0.2) (size 0.38 1.72) (layers "B.Cu" "B.Mask")
      (net 209 "I3C[2]_SDA_1V0") (pinfunction "OA10") (pintype "passive"))
    (pad "OA11" smd rect (at -24.4 -0.2) (size 0.38 1.72) (layers "B.Cu" "B.Mask")
      (net 204 "I3C[3]_SCL_1V0") (pinfunction "OA11") (pintype "passive"))
    (pad "OA12" smd rect (at -23.8 -0.2) (size 0.38 1.72) (layers "B.Cu" "B.Mask")
      (net 203 "I3C[3]_SDA_1V0") (pinfunction "OA12") (pintype "passive"))
    (pad "OA13" smd rect (at -23.2 0) (size 0.38 2.12) (layers "B.Cu" "B.Mask")
      (net 1 "GND") (pinfunction "OA13") (pintype "passive"))
    (pad "OA14" smd rect (at -22.6 -0.2) (size 0.38 1.72) (layers "B.Cu" "B.Mask")
      (net 102 "VIRTUAL_RESEAT") (pinfunction "OA14") (pintype "passive"))
    (pad "OB1" smd rect (at -30.4 -0.2) (size 0.38 1.72) (layers "F.Cu" "F.Mask")
      (net 57 "P12V_AUX") (pinfunction "OB1") (pintype "passive"))
    (pad "OB2" smd rect (at -29.8 -0.2) (size 0.38 1.72) (layers "F.Cu" "F.Mask")
      (net 57 "P12V_AUX") (pinfunction "OB2") (pintype "passive"))
    (pad "OB3" smd rect (at -29.2 -0.2) (size 0.38 1.72) (layers "F.Cu" "F.Mask")
      (net 58 "PRSNT0_N") (pinfunction "OB3") (pintype "passive"))
    (pad "OB4" smd rect (at -28.6 0) (size 0.38 2.12) (layers "F.Cu" "F.Mask")
      (net 1 "GND") (pinfunction "OB4") (pintype "passive"))
    (pad "OB5" smd rect (at -28 -0.2) (size 0.38 1.72) (layers "F.Cu" "F.Mask")
      (net 46 "UART1_SCM_TX") (pinfunction "OB5") (pintype "passive"))
    (pad "OB6" smd rect (at -27.4 -0.2) (size 0.38 1.72) (layers "F.Cu" "F.Mask")
      (net 39 "UART1_SCM_RX") (pinfunction "OB6") (pintype "passive"))
    (pad "OB7" smd rect (at -26.8 0) (size 0.38 2.12) (layers "F.Cu" "F.Mask")
      (net 1 "GND") (pinfunction "OB7") (pintype "passive"))
    (pad "OB8" smd rect (at -26.2 -0.2) (size 0.38 1.72) (layers "F.Cu" "F.Mask")
      (net 41 "UART0_SCM_TX") (pinfunction "OB8") (pintype "passive"))
    (pad "OB9" smd rect (at -25.6 -0.2) (size 0.38 1.72) (layers "F.Cu" "F.Mask")
      (net 45 "UART0_SCM_RX") (pinfunction "OB9") (pintype "passive"))
    (pad "OB10" smd rect (at -25 0) (size 0.38 2.12) (layers "F.Cu" "F.Mask")
      (net 1 "GND") (pinfunction "OB10") (pintype "passive"))
    (pad "OB11" smd rect (at -24.4 -0.2) (size 0.38 1.72) (layers "F.Cu" "F.Mask")
      (net 54 "SPI0_CLK") (pinfunction "OB11") (pintype "passive"))
    (pad "OB12" smd rect (at -23.8 -0.2) (size 0.38 1.72) (layers "F.Cu" "F.Mask")
      (net 53 "SPI0_CS_N") (pinfunction "OB12") (pintype "passive"))
    (pad "OB13" smd rect (at -23.2 -0.2) (size 0.38 1.72) (layers "F.Cu" "F.Mask")
      (net 55 "SPI0_MOSI") (pinfunction "OB13") (pintype "passive"))
    (pad "OB14" smd rect (at -22.6 -0.2) (size 0.38 1.72) (layers "F.Cu" "F.Mask")
      (net 56 "SPI0_MISO") (pinfunction "OB14") (pintype "passive"))
  )
)
